# S9S_MB_2U (Grand Teton) — schematic netlist excerpt (pin names and nets, part order shuffled) for the footprints in the layout excerpt that follows; sources: Cadence DE-HDL packaged netlist, KiCad conversion of 03242023_DA0F0TMBIJ0_F0T_Motherboard_J_brd_V01_OCP.brd

C545  Q_CAP  1UF 25V 10% X6S  pkg C0402  page 132 : A = P3V3_AUX ; B = GND

X15  TP_TDR_4P_FTS  TP_TDR_4P_DIP EMPTY  pkg TH  page 309
  S1  = TDR_DIFF_100_IN2_DP
  P1  = T1_GND
  P2  = T1_GND
  S2  = TDR_DIFF_100_IN2_DN

(kicad_pcb
	(version 20260206)
	(generator "pcbnew")
	(generator_version "10.0")
	(general
		(thickness 1.6)
		(legacy_teardrops no)
	)
	(paper "A4")
	(title_block
		(title "03242023_DA0F0TMBIJ0_F0T_Motherboard_J_brd_V01_OCP.brd")
		(comment 1 "Grand Teton / footprints 3560-3561 of 6105")
	)
	(layers
		(0 "F.Cu" signal "TOP")
		(4 "In1.Cu" signal "GND")
		(6 "In2.Cu" signal "IN1")
		(8 "In3.Cu" signal "GND1")
		(10 "In4.Cu" signal "IN2")
		(12 "In5.Cu" signal "GND2")
		(14 "In6.Cu" signal "IN3")
		(16 "In7.Cu" signal "GND3")
		(18 "In8.Cu" signal "VCC")
		(20 "In9.Cu" signal "VCC1")
		(22 "In10.Cu" signal "GND4")
		(24 "In11.Cu" signal "IN4")
		(26 "In12.Cu" signal "GND5")
		(28 "In13.Cu" signal "IN5")
		(30 "In14.Cu" signal "GND6")
		(32 "In15.Cu" signal "IN6")
		(34 "In16.Cu" signal "GND7")
		(2 "B.Cu" signal "BOTTOM")
		(9 "F.Adhes" user "F.Adhesive")
		(11 "B.Adhes" user "B.Adhesive")
		(13 "F.Paste" user "Package Geometry/Pastemask Top")
		(15 "B.Paste" user "Package Geometry/Pastemask Bottom")
		(5 "F.SilkS" user "Ref Des/Silkscreen Top")
		(7 "B.SilkS" user "Ref Des/Silkscreen Bottom")
		(1 "F.Mask" user "Board Geometry/Soldermask Top")
		(3 "B.Mask" user "Board Geometry/Soldermask Bottom")
		(17 "Dwgs.User" user "User.Drawings")
		(19 "Cmts.User" user "User.Comments")
		(21 "Eco1.User" user "User.Eco1")
		(23 "Eco2.User" user "User.Eco2")
		(25 "Edge.Cuts" user "Board Geometry/Outline")
		(27 "Margin" user)
		(31 "F.CrtYd" user "Package Geometry/Place Bound Top")
		(29 "B.CrtYd" user "Package Geometry/Place Bound Bottom")
		(35 "F.Fab" user "Ref Des/Assembly Top")
		(33 "B.Fab" user "Ref Des/Assembly Bottom")
	)
	(footprint ""
		(layer "F.Cu")
		(at 372.207282 -61.581792)
		(property "Reference" "C545"
			(at 0 0 0)
			(layer "F.SilkS")
			(hide yes)
			(effects
				(font
					(size 1.27 1.27)
				)
			)
		)
		(property "Value" ""
			(at 0 0 0)
			(layer "F.Fab")
			(effects
				(font
					(size 1.27 1.27)
				)
			)
		)
		(duplicate_pad_numbers_are_jumpers no)
		(fp_line
			(start -0.7874 -0.4064)
			(end 0.7874 -0.4064)
			(stroke
				(width 0.1524)
				(type default)
			)
			(layer "F.SilkS")
		)
		(fp_line
			(start -0.7874 0.4064)
			(end -0.7874 -0.4064)
			(stroke
				(width 0.1524)
				(type default)
			)
			(layer "F.SilkS")
		)
		(fp_line
			(start 0.7874 -0.4064)
			(end 0.7874 0.4064)
			(stroke
				(width 0.1524)
				(type default)
			)
			(layer "F.SilkS")
		)
		(fp_line
			(start 0.7874 0.4064)
			(end -0.7874 0.4064)
			(stroke
				(width 0.1524)
				(type default)
			)
			(layer "F.SilkS")
		)
		(fp_line
			(start -0.67945 -0.305054)
			(end -0.12065 -0.305054)
			(stroke
				(width 0.1)
				(type default)
			)
			(layer "F.Fab")
		)
		(fp_line
			(start -0.67945 0.3048)
			(end -0.67945 -0.305054)
			(stroke
				(width 0.1)
				(type default)
			)
			(layer "F.Fab")
		)
		(fp_line
			(start -0.12065 -0.305054)
			(end -0.12065 -0.2794)
			(stroke
				(width 0.1)
				(type default)
			)
			(layer "F.Fab")
		)
		(fp_line
			(start -0.12065 -0.2794)
			(end 0.12065 -0.2794)
			(stroke
				(width 0.1)
				(type default)
			)
			(layer "F.Fab")
		)
		(fp_line
			(start -0.12065 0.2794)
			(end -0.12065 0.3048)
			(stroke
				(width 0.1)
				(type default)
			)
			(layer "F.Fab")
		)
		(fp_line
			(start -0.12065 0.3048)
			(end -0.67945 0.3048)
			(stroke
				(width 0.1)
				(type default)
			)
			(layer "F.Fab")
		)
		(fp_line
			(start 0.120396 0.2794)
			(end -0.12065 0.2794)
			(stroke
				(width 0.1)
				(type default)
			)
			(layer "F.Fab")
		)
		(fp_line
			(start 0.120396 0.3048)
			(end 0.120396 0.2794)
			(stroke
				(width 0.1)
				(type default)
			)
			(layer "F.Fab")
		)
		(fp_line
			(start 0.12065 -0.3048)
			(end 0.67945 -0.3048)
			(stroke
				(width 0.1)
				(type default)
			)
			(layer "F.Fab")
		)
		(fp_line
			(start 0.12065 -0.2794)
			(end 0.12065 -0.3048)
			(stroke
				(width 0.1)
				(type default)
			)
			(layer "F.Fab")
		)
		(fp_line
			(start 0.67945 -0.3048)
			(end 0.67945 0.3048)
			(stroke
				(width 0.1)
				(type default)
			)
			(layer "F.Fab")
		)
		(fp_line
			(start 0.67945 0.3048)
			(end 0.120396 0.3048)
			(stroke
				(width 0.1)
				(type default)
			)
			(layer "F.Fab")
		)
		(pad "1" smd circle
			(at -0.40005 0)
			(size 0 0)
			(layers "F.Cu" "F.Mask" "F.Paste")
			(net "P3V3_AUX")
		)
		(pad "2" smd circle
			(at 0.40005 0)
			(size 0 0)
			(layers "F.Cu" "F.Mask" "F.Paste")
			(net "GND")
		)
	)
	(footprint ""
		(layer "F.Cu")
		(at 498.693948 -148.08454 90)
		(property "Reference" "X15"
			(at -3.42646 3.325622 90)
			(unlocked yes)
			(layer "F.SilkS")
			(effects
				(font
					(size 0.7874 0.5842)
					(thickness 0.1524)
				)
				(justify left)
			)
		)
		(property "Value" ""
			(at 0 0 90)
			(layer "F.Fab")
			(effects
				(font
					(size 1.27 1.27)
				)
			)
		)
		(property "Device Type" "TP_TDR_4P_FTS_MPKT4_H025P0200_I"
			(at 1.30175 1.27 180)
			(unlocked yes)
			(layer "F.Fab")
			(hide yes)
			(effects
				(font
					(size 0.635 0.4064)
					(thickness 0.1524)
				)
			)
		)
		(property "User Part Number" "TP15"
			(at 1.30175 1.27 180)
			(unlocked yes)
			(layer "Cmts.User")
			(hide yes)
			(effects
				(font
					(size 0.635 0.4064)
					(thickness 0.1524)
				)
			)
		)
		(duplicate_pad_numbers_are_jumpers no)
		(fp_line
			(start 2.54 -1.27)
			(end 0 -1.27)
			(stroke
				(width 0.1524)
				(type default)
			)
			(layer "F.SilkS")
		)
		(fp_line
			(start 0 -1.27)
			(end 0 -0.635)
			(stroke
				(width 0.1524)
				(type default)
			)
			(layer "F.SilkS")
		)
		(fp_line
			(start 2.54 -1.1303)
			(end 2.54 -1.27)
			(stroke
				(width 0.1524)
				(type default)
			)
			(layer "F.SilkS")
		)
		(fp_line
			(start 0 0.635)
			(end 0 1.905)
			(stroke
				(width 0.1524)
				(type default)
			)
			(layer "F.SilkS")
		)
		(fp_line
			(start 2.54 1.4097)
			(end 2.54 1.1303)
			(stroke
				(width 0.1524)
				(type default)
			)
			(layer "F.SilkS")
		)
		(fp_line
			(start 0 3.175)
			(end 0 3.81)
			(stroke
				(width 0.1524)
				(type default)
			)
			(layer "F.SilkS")
		)
		(fp_line
			(start 2.54 3.81)
			(end 2.54 3.6703)
			(stroke
				(width 0.1524)
				(type default)
			)
			(layer "F.SilkS")
		)
		(fp_line
			(start 0 3.81)
			(end 2.54 3.81)
			(stroke
				(width 0.1524)
				(type default)
			)
			(layer "F.SilkS")
		)
		(fp_poly
			(pts
				(xy -0.761746 0) (xy -2.285746 0.762) (xy -2.285746 -0.762)
			)
			(stroke
				(width 0)
				(type default)
			)
			(fill yes)
			(layer "F.SilkS")
		)
		(fp_line
			(start 2.54 -1.27)
			(end 0 -1.27)
			(stroke
				(width 0.1)
				(type default)
			)
			(layer "F.Fab")
		)
		(fp_line
			(start 0 -1.27)
			(end 0 3.81)
			(stroke
				(width 0.1)
				(type default)
			)
			(layer "F.Fab")
		)
		(fp_line
			(start 2.54 3.81)
			(end 2.54 -1.27)
			(stroke
				(width 0.1)
				(type default)
			)
			(layer "F.Fab")
		)
		(fp_line
			(start 0 3.81)
			(end 2.54 3.81)
			(stroke
				(width 0.1)
				(type default)
			)
			(layer "F.Fab")
		)
		(fp_poly
			(pts
				(xy -0.761746 0) (xy -2.285746 -0.762) (xy -2.285746 0.762)
			)
			(stroke
				(width 0)
				(type default)
			)
			(fill yes)
			(layer "F.Fab")
		)
		(pad "1" thru_hole circle
			(at 0 0 90)
			(size 1.0033 1.0033)
			(drill 0.249936)
			(layers "*.Cu" "*.Mask")
			(remove_unused_layers no)
			(net "TDR_DIFF_100_IN2_DP")
			(clearance 0.10795)
			(thermal_gap 0.10795)
			(padstack
				(mode front_inner_back)
				(layer "Inner"
					(shape circle)
					(size 0.8001 0.8001)
					(clearance 0.1524)
				)
				(layer "B.Cu"
					(shape circle)
					(size 1.0033 1.0033)
					(clearance 0.10795)
				)
			)
		)
		(pad "2" thru_hole circle
			(at 2.54 0 90)
			(size 1.9939 1.9939)
			(drill 0.249936)
			(layers "*.Cu" "*.Mask")
			(remove_unused_layers no)
			(net "T1_GND")
			(clearance 0.10795)
			(thermal_gap 0.10795)
			(padstack
				(mode front_inner_back)
				(layer "Inner"
					(shape circle)
					(size 0.8001 0.8001)
					(clearance 0.1524)
				)
				(layer "B.Cu"
					(shape circle)
					(size 1.9939 1.9939)
					(clearance 0.10795)
				)
			)
		)
		(pad "3" thru_hole circle
			(at 2.54 2.54 90)
			(size 1.9939 1.9939)
			(drill 0.249936)
			(layers "*.Cu" "*.Mask")
			(remove_unused_layers no)
			(net "T1_GND")
			(clearance 0.10795)
			(thermal_gap 0.10795)
			(padstack
				(mode front_inner_back)
				(layer "Inner"
					(shape circle)
					(size 0.8001 0.8001)
					(clearance 0.1524)
				)
				(layer "B.Cu"
					(shape circle)
					(size 1.9939 1.9939)
					(clearance 0.10795)
				)
			)
		)
		(pad "4" thru_hole circle
			(at 0 2.54 90)
			(size 1.0033 1.0033)
			(drill 0.249936)
			(layers "*.Cu" "*.Mask")
			(remove_unused_layers no)
			(net "TDR_DIFF_100_IN2_DN")
			(clearance 0.10795)
			(thermal_gap 0.10795)
			(padstack
				(mode front_inner_back)
				(layer "Inner"
					(shape circle)
					(size 0.8001 0.8001)
					(clearance 0.1524)
				)
				(layer "B.Cu"
					(shape circle)
					(size 1.0033 1.0033)
					(clearance 0.10795)
				)
			)
		)
	)
)
